(kicad_pcb
	(version 20260206)
	(generator "pcbnew")
	(generator_version "10.0")
	(general
		(thickness 1.6)
		(legacy_teardrops no)
	)
	(paper "A4")
	(title_block
		(title "panther-plus-userver — 13130-1b_20150205.brd")
		(comment 1 "Honey Badger (Wiwynn) / footprint 406 of 1509 (DIMM2), pads 114-120 of 210")
	)
	(layers
		(0 "F.Cu" signal "TOP")
		(4 "In1.Cu" signal "L2")
		(6 "In2.Cu" signal "L3")
		(8 "In3.Cu" signal "L4")
		(10 "In4.Cu" signal "L5")
		(12 "In5.Cu" signal "L6")
		(14 "In6.Cu" signal "L7")
		(16 "In7.Cu" signal "L8")
		(18 "In8.Cu" signal "L9")
		(20 "In9.Cu" signal "L10")
		(22 "In10.Cu" signal "L11")
		(2 "B.Cu" signal "BOTTOM")
		(9 "F.Adhes" user "F.Adhesive")
		(11 "B.Adhes" user "B.Adhesive")
		(13 "F.Paste" user "Package Geometry/Pastemask Top")
		(15 "B.Paste" user "Package Geometry/Pastemask Bottom")
		(5 "F.SilkS" user "Ref Des/Silkscreen Top")
		(7 "B.SilkS" user "Ref Des/Silkscreen Bottom")
		(1 "F.Mask" user "Board Geometry/Soldermask Top")
		(3 "B.Mask" user "Board Geometry/Soldermask Bottom")
		(17 "Dwgs.User" user "User.Drawings")
		(19 "Cmts.User" user "User.Comments")
		(21 "Eco1.User" user "User.Eco1")
		(23 "Eco2.User" user "User.Eco2")
		(25 "Edge.Cuts" user "Board Geometry/Outline")
		(27 "Margin" user)
		(31 "F.CrtYd" user "Package Geometry/Place Bound Top")
		(29 "B.CrtYd" user "Package Geometry/Place Bound Bottom")
		(35 "F.Fab" user "Ref Des/Assembly Top")
		(33 "B.Fab" user "Ref Des/Assembly Bottom")
	)
	(footprint ""
		(layer "F.Cu")
		(at 158.500064 -66.699892 180)
		(property "Reference" "DIMM2"
			(at 0 0 180)
			(layer "F.SilkS")
			(hide yes)
			(effects
				(font
					(size 1.27 1.27)
				)
			)
		)
		(property "Value" "DDR3-204P-174-COLAY-1-GP"
			(at -40.682164 -17.468088 180)
			(unlocked yes)
			(layer "F.Fab")
			(hide yes)
			(effects
				(font
					(size 1.016 1.016)
					(thickness 0.1524)
				)
			)
		)
		(property "Device Type" "AS0A626-H8SN-7H-COLAY-1"
			(at -40.682164 -18.992088 180)
			(unlocked yes)
			(layer "F.Fab")
			(hide yes)
			(effects
				(font
					(size 1.016 1.016)
					(thickness 0.1524)
				)
			)
		)
		(duplicate_pad_numbers_are_jumpers no)
		(pad "112" smd custom
			(at 4.05003 -4.106672 180)
			(size 0.1143 0.1143)
			(layers "F.Cu" "F.Mask" "F.Paste")
			(net "M_A_CK_DP3")
			(options
				(clearance outline)
				(anchor circle)
			)
			(primitives
				(gr_poly
					(pts
						(xy 0 0.9017) (xy -0.03175 0.89916) (xy -0.0635 0.889) (xy -0.09144 0.87376) (xy -0.11684 0.85344)
						(xy -0.13716 0.82804) (xy -0.1524 0.8001) (xy -0.16256 0.76835) (xy -0.1651 0.7366) (xy -0.1651 0.19685)
						(xy -0.17272 0.18923) (xy -0.17907 0.18034) (xy -0.18669 0.17145) (xy -0.19177 0.16256) (xy -0.19812 0.15367)
						(xy -0.20828 0.13335) (xy -0.21971 0.10287) (xy -0.22225 0.09271) (xy -0.22479 0.08128) (xy -0.22606 0.07112)
						(xy -0.2286 0.05969) (xy -0.2286 0.01651) (xy -0.22606 0.00508) (xy -0.22479 -0.00508) (xy -0.22225 -0.01651)
						(xy -0.21971 -0.02667) (xy -0.20828 -0.05715) (xy -0.19812 -0.07747) (xy -0.19177 -0.08636) (xy -0.18669 -0.09525)
						(xy -0.17907 -0.10414) (xy -0.17272 -0.11303) (xy -0.1651 -0.12065) (xy -0.1651 -0.7366) (xy -0.16256 -0.76835)
						(xy -0.1524 -0.8001) (xy -0.13716 -0.82804) (xy -0.11684 -0.85344) (xy -0.09144 -0.87376) (xy -0.0635 -0.889)
						(xy -0.03175 -0.89916) (xy 0 -0.9017) (xy 0.03175 -0.89916) (xy 0.0635 -0.889) (xy 0.09144 -0.87376)
						(xy 0.11684 -0.85344) (xy 0.13716 -0.82804) (xy 0.1524 -0.8001) (xy 0.16256 -0.76835) (xy 0.1651 -0.7366)
						(xy 0.1651 -0.11938) (xy 0.17272 -0.11176) (xy 0.19812 -0.0762) (xy 0.2032 -0.06604) (xy 0.20701 -0.05715)
						(xy 0.21209 -0.04699) (xy 0.2159 -0.03683) (xy 0.21844 -0.02667) (xy 0.22225 -0.01524) (xy 0.22352 -0.00508)
						(xy 0.22606 0.00508) (xy 0.22733 0.01651) (xy 0.22733 0.02667) (xy 0.2286 0.0381) (xy 0.22733 0.04953)
						(xy 0.22733 0.05969) (xy 0.22606 0.07112) (xy 0.22352 0.08128) (xy 0.22225 0.09144) (xy 0.21844 0.10287)
						(xy 0.2159 0.11303) (xy 0.21209 0.12319) (xy 0.20701 0.13335) (xy 0.2032 0.14224) (xy 0.19812 0.1524)
						(xy 0.17272 0.18796) (xy 0.1651 0.19558) (xy 0.1651 0.7366) (xy 0.16256 0.76835) (xy 0.1524 0.8001)
						(xy 0.13716 0.82804) (xy 0.11684 0.85344) (xy 0.09144 0.87376) (xy 0.0635 0.889) (xy 0.03175 0.89916)
					)
					(width 0)
					(fill yes)
				)
			)
		)
		(pad "113" smd custom
			(at 4.350004 4.106672 180)
			(size 0.1143 0.1143)
			(layers "F.Cu" "F.Mask" "F.Paste")
			(net "M_A_CK_DN2")
			(options
				(clearance outline)
				(anchor circle)
			)
			(primitives
				(gr_poly
					(pts
						(xy 0 0.9017) (xy -0.03175 0.89916) (xy -0.0635 0.889) (xy -0.09144 0.87376) (xy -0.11684 0.85344)
						(xy -0.13716 0.82804) (xy -0.1524 0.8001) (xy -0.16256 0.76835) (xy -0.1651 0.7366) (xy -0.1651 -0.13462)
						(xy -0.17272 -0.14224) (xy -0.19812 -0.1778) (xy -0.2032 -0.18796) (xy -0.20701 -0.19685) (xy -0.21209 -0.20701)
						(xy -0.2159 -0.21717) (xy -0.21844 -0.22733) (xy -0.22225 -0.23876) (xy -0.22352 -0.24892) (xy -0.22606 -0.25908)
						(xy -0.22733 -0.27051) (xy -0.22733 -0.28067) (xy -0.2286 -0.2921) (xy -0.22733 -0.30353) (xy -0.22733 -0.31369)
						(xy -0.22606 -0.32512) (xy -0.22352 -0.33528) (xy -0.22225 -0.34544) (xy -0.21844 -0.35687) (xy -0.2159 -0.36703)
						(xy -0.21209 -0.37719) (xy -0.20701 -0.38735) (xy -0.2032 -0.39624) (xy -0.19812 -0.4064) (xy -0.17272 -0.44196)
						(xy -0.1651 -0.44958) (xy -0.1651 -0.7366) (xy -0.16256 -0.76835) (xy -0.1524 -0.8001) (xy -0.13716 -0.82804)
						(xy -0.11684 -0.85344) (xy -0.09144 -0.87376) (xy -0.0635 -0.889) (xy -0.03175 -0.89916) (xy 0 -0.9017)
						(xy 0.03175 -0.89916) (xy 0.0635 -0.889) (xy 0.09144 -0.87376) (xy 0.11684 -0.85344) (xy 0.13716 -0.82804)
						(xy 0.1524 -0.8001) (xy 0.16256 -0.76835) (xy 0.1651 -0.7366) (xy 0.1651 -0.44958) (xy 0.17272 -0.44196)
						(xy 0.19812 -0.4064) (xy 0.2032 -0.39624) (xy 0.20701 -0.38735) (xy 0.21209 -0.37719) (xy 0.2159 -0.36703)
						(xy 0.21844 -0.35687) (xy 0.22225 -0.34544) (xy 0.22352 -0.33528) (xy 0.22606 -0.32512) (xy 0.22733 -0.31369)
						(xy 0.22733 -0.30353) (xy 0.2286 -0.2921) (xy 0.22733 -0.28067) (xy 0.22733 -0.27051) (xy 0.22606 -0.25908)
						(xy 0.22352 -0.24892) (xy 0.22225 -0.23876) (xy 0.21844 -0.22733) (xy 0.2159 -0.21717) (xy 0.21209 -0.20701)
						(xy 0.20701 -0.19685) (xy 0.2032 -0.18796) (xy 0.19812 -0.1778) (xy 0.17272 -0.14224) (xy 0.1651 -0.13462)
						(xy 0.1651 0.7366) (xy 0.16256 0.76835) (xy 0.1524 0.8001) (xy 0.13716 0.82804) (xy 0.11684 0.85344)
						(xy 0.09144 0.87376) (xy 0.0635 0.889) (xy 0.03175 0.89916)
					)
					(width 0)
					(fill yes)
				)
			)
		)
		(pad "114" smd custom
			(at 4.649978 -4.106672 180)
			(size 0.1143 0.1143)
			(layers "F.Cu" "F.Mask" "F.Paste")
			(net "M_A_CK_DN3")
			(options
				(clearance outline)
				(anchor circle)
			)
			(primitives
				(gr_poly
					(pts
						(xy 0 0.9017) (xy -0.03175 0.89916) (xy -0.0635 0.889) (xy -0.09144 0.87376) (xy -0.11684 0.85344)
						(xy -0.13716 0.82804) (xy -0.1524 0.8001) (xy -0.16256 0.76835) (xy -0.1651 0.7366) (xy -0.1651 0.44958)
						(xy -0.17272 0.44196) (xy -0.19812 0.4064) (xy -0.2032 0.39624) (xy -0.20701 0.38735) (xy -0.21209 0.37719)
						(xy -0.2159 0.36703) (xy -0.21844 0.35687) (xy -0.22225 0.34544) (xy -0.22352 0.33528) (xy -0.22606 0.32512)
						(xy -0.22733 0.31369) (xy -0.22733 0.30353) (xy -0.2286 0.2921) (xy -0.22733 0.28067) (xy -0.22733 0.27051)
						(xy -0.22606 0.25908) (xy -0.22352 0.24892) (xy -0.22225 0.23876) (xy -0.21844 0.22733) (xy -0.2159 0.21717)
						(xy -0.21209 0.20701) (xy -0.20701 0.19685) (xy -0.2032 0.18796) (xy -0.19812 0.1778) (xy -0.17272 0.14224)
						(xy -0.1651 0.13462) (xy -0.1651 -0.7366) (xy -0.16256 -0.76835) (xy -0.1524 -0.8001) (xy -0.13716 -0.82804)
						(xy -0.11684 -0.85344) (xy -0.09144 -0.87376) (xy -0.0635 -0.889) (xy -0.03175 -0.89916) (xy 0 -0.9017)
						(xy 0.03175 -0.89916) (xy 0.0635 -0.889) (xy 0.09144 -0.87376) (xy 0.11684 -0.85344) (xy 0.13716 -0.82804)
						(xy 0.1524 -0.8001) (xy 0.16256 -0.76835) (xy 0.1651 -0.7366) (xy 0.1651 0.13462) (xy 0.17272 0.14224)
						(xy 0.19812 0.1778) (xy 0.2032 0.18796) (xy 0.20701 0.19685) (xy 0.21209 0.20701) (xy 0.2159 0.21717)
						(xy 0.21844 0.22733) (xy 0.22225 0.23876) (xy 0.22352 0.24892) (xy 0.22606 0.25908) (xy 0.22733 0.27051)
						(xy 0.22733 0.28067) (xy 0.2286 0.2921) (xy 0.22733 0.30353) (xy 0.22733 0.31369) (xy 0.22606 0.32512)
						(xy 0.22352 0.33528) (xy 0.22225 0.34544) (xy 0.21844 0.35687) (xy 0.2159 0.36703) (xy 0.21209 0.37719)
						(xy 0.20701 0.38735) (xy 0.2032 0.39624) (xy 0.19812 0.4064) (xy 0.17272 0.44196) (xy 0.1651 0.44958)
						(xy 0.1651 0.7366) (xy 0.16256 0.76835) (xy 0.1524 0.8001) (xy 0.13716 0.82804) (xy 0.11684 0.85344)
						(xy 0.09144 0.87376) (xy 0.0635 0.889) (xy 0.03175 0.89916)
					)
					(width 0)
					(fill yes)
				)
			)
		)
		(pad "115" smd custom
			(at 4.949952 4.106672 180)
			(size 0.1143 0.1143)
			(layers "F.Cu" "F.Mask" "F.Paste")
			(net "PV_VDDR")
			(options
				(clearance outline)
				(anchor circle)
			)
			(primitives
				(gr_poly
					(pts
						(xy 0 0.9017) (xy -0.03175 0.89916) (xy -0.0635 0.889) (xy -0.09144 0.87376) (xy -0.11684 0.85344)
						(xy -0.13716 0.82804) (xy -0.1524 0.8001) (xy -0.16256 0.76835) (xy -0.1651 0.7366) (xy -0.1651 0.11938)
						(xy -0.17272 0.11176) (xy -0.19812 0.0762) (xy -0.2032 0.06604) (xy -0.20701 0.05715) (xy -0.21209 0.04699)
						(xy -0.2159 0.03683) (xy -0.21844 0.02667) (xy -0.22225 0.01524) (xy -0.22352 0.00508) (xy -0.22606 -0.00508)
						(xy -0.22733 -0.01651) (xy -0.22733 -0.02667) (xy -0.2286 -0.0381) (xy -0.22733 -0.04953) (xy -0.22733 -0.05969)
						(xy -0.22606 -0.07112) (xy -0.22352 -0.08128) (xy -0.22225 -0.09144) (xy -0.21844 -0.10287) (xy -0.2159 -0.11303)
						(xy -0.21209 -0.12319) (xy -0.20701 -0.13335) (xy -0.2032 -0.14224) (xy -0.19812 -0.1524) (xy -0.17272 -0.18796)
						(xy -0.1651 -0.19558) (xy -0.1651 -0.7366) (xy -0.16256 -0.76835) (xy -0.1524 -0.8001) (xy -0.13716 -0.82804)
						(xy -0.11684 -0.85344) (xy -0.09144 -0.87376) (xy -0.0635 -0.889) (xy -0.03175 -0.89916) (xy 0 -0.9017)
						(xy 0.03175 -0.89916) (xy 0.0635 -0.889) (xy 0.09144 -0.87376) (xy 0.11684 -0.85344) (xy 0.13716 -0.82804)
						(xy 0.1524 -0.8001) (xy 0.16256 -0.76835) (xy 0.1651 -0.7366) (xy 0.1651 -0.19685) (xy 0.17272 -0.18923)
						(xy 0.17907 -0.18034) (xy 0.18669 -0.17145) (xy 0.19177 -0.16256) (xy 0.19812 -0.15367) (xy 0.20828 -0.13335)
						(xy 0.21971 -0.10287) (xy 0.22225 -0.09271) (xy 0.22479 -0.08128) (xy 0.22606 -0.07112) (xy 0.2286 -0.05969)
						(xy 0.2286 -0.01651) (xy 0.22606 -0.00508) (xy 0.22479 0.00508) (xy 0.22225 0.01651) (xy 0.21971 0.02667)
						(xy 0.20828 0.05715) (xy 0.19812 0.07747) (xy 0.19177 0.08636) (xy 0.18669 0.09525) (xy 0.17907 0.10414)
						(xy 0.17272 0.11303) (xy 0.1651 0.12065) (xy 0.1651 0.7366) (xy 0.16256 0.76835) (xy 0.1524 0.8001)
						(xy 0.13716 0.82804) (xy 0.11684 0.85344) (xy 0.09144 0.87376) (xy 0.0635 0.889) (xy 0.03175 0.89916)
					)
					(width 0)
					(fill yes)
				)
			)
		)
		(pad "116" smd custom
			(at 5.249926 -4.106672 180)
			(size 0.1143 0.1143)
			(layers "F.Cu" "F.Mask" "F.Paste")
			(net "PV_VDDR")
			(options
				(clearance outline)
				(anchor circle)
			)
			(primitives
				(gr_poly
					(pts
						(xy 0 0.9017) (xy -0.03175 0.89916) (xy -0.0635 0.889) (xy -0.09144 0.87376) (xy -0.11684 0.85344)
						(xy -0.13716 0.82804) (xy -0.1524 0.8001) (xy -0.16256 0.76835) (xy -0.1651 0.7366) (xy -0.1651 0.19685)
						(xy -0.17272 0.18923) (xy -0.17907 0.18034) (xy -0.18669 0.17145) (xy -0.19177 0.16256) (xy -0.19812 0.15367)
						(xy -0.20828 0.13335) (xy -0.21971 0.10287) (xy -0.22225 0.09271) (xy -0.22479 0.08128) (xy -0.22606 0.07112)
						(xy -0.2286 0.05969) (xy -0.2286 0.01651) (xy -0.22606 0.00508) (xy -0.22479 -0.00508) (xy -0.22225 -0.01651)
						(xy -0.21971 -0.02667) (xy -0.20828 -0.05715) (xy -0.19812 -0.07747) (xy -0.19177 -0.08636) (xy -0.18669 -0.09525)
						(xy -0.17907 -0.10414) (xy -0.17272 -0.11303) (xy -0.1651 -0.12065) (xy -0.1651 -0.7366) (xy -0.16256 -0.76835)
						(xy -0.1524 -0.8001) (xy -0.13716 -0.82804) (xy -0.11684 -0.85344) (xy -0.09144 -0.87376) (xy -0.0635 -0.889)
						(xy -0.03175 -0.89916) (xy 0 -0.9017) (xy 0.03175 -0.89916) (xy 0.0635 -0.889) (xy 0.09144 -0.87376)
						(xy 0.11684 -0.85344) (xy 0.13716 -0.82804) (xy 0.1524 -0.8001) (xy 0.16256 -0.76835) (xy 0.1651 -0.7366)
						(xy 0.1651 -0.11938) (xy 0.17272 -0.11176) (xy 0.19812 -0.0762) (xy 0.2032 -0.06604) (xy 0.20701 -0.05715)
						(xy 0.21209 -0.04699) (xy 0.2159 -0.03683) (xy 0.21844 -0.02667) (xy 0.22225 -0.01524) (xy 0.22352 -0.00508)
						(xy 0.22606 0.00508) (xy 0.22733 0.01651) (xy 0.22733 0.02667) (xy 0.2286 0.0381) (xy 0.22733 0.04953)
						(xy 0.22733 0.05969) (xy 0.22606 0.07112) (xy 0.22352 0.08128) (xy 0.22225 0.09144) (xy 0.21844 0.10287)
						(xy 0.2159 0.11303) (xy 0.21209 0.12319) (xy 0.20701 0.13335) (xy 0.2032 0.14224) (xy 0.19812 0.1524)
						(xy 0.17272 0.18796) (xy 0.1651 0.19558) (xy 0.1651 0.7366) (xy 0.16256 0.76835) (xy 0.1524 0.8001)
						(xy 0.13716 0.82804) (xy 0.11684 0.85344) (xy 0.09144 0.87376) (xy 0.0635 0.889) (xy 0.03175 0.89916)
					)
					(width 0)
					(fill yes)
				)
			)
		)
		(pad "117" smd custom
			(at 5.5499 4.106672 180)
			(size 0.1143 0.1143)
			(layers "F.Cu" "F.Mask" "F.Paste")
			(net "M_A_MA10")
			(options
				(clearance outline)
				(anchor circle)
			)
			(primitives
				(gr_poly
					(pts
						(xy 0 0.9017) (xy -0.03175 0.89916) (xy -0.0635 0.889) (xy -0.09144 0.87376) (xy -0.11684 0.85344)
						(xy -0.13716 0.82804) (xy -0.1524 0.8001) (xy -0.16256 0.76835) (xy -0.1651 0.7366) (xy -0.1651 -0.13462)
						(xy -0.17272 -0.14224) (xy -0.19812 -0.1778) (xy -0.2032 -0.18796) (xy -0.20701 -0.19685) (xy -0.21209 -0.20701)
						(xy -0.2159 -0.21717) (xy -0.21844 -0.22733) (xy -0.22225 -0.23876) (xy -0.22352 -0.24892) (xy -0.22606 -0.25908)
						(xy -0.22733 -0.27051) (xy -0.22733 -0.28067) (xy -0.2286 -0.2921) (xy -0.22733 -0.30353) (xy -0.22733 -0.31369)
						(xy -0.22606 -0.32512) (xy -0.22352 -0.33528) (xy -0.22225 -0.34544) (xy -0.21844 -0.35687) (xy -0.2159 -0.36703)
						(xy -0.21209 -0.37719) (xy -0.20701 -0.38735) (xy -0.2032 -0.39624) (xy -0.19812 -0.4064) (xy -0.17272 -0.44196)
						(xy -0.1651 -0.44958) (xy -0.1651 -0.7366) (xy -0.16256 -0.76835) (xy -0.1524 -0.8001) (xy -0.13716 -0.82804)
						(xy -0.11684 -0.85344) (xy -0.09144 -0.87376) (xy -0.0635 -0.889) (xy -0.03175 -0.89916) (xy 0 -0.9017)
						(xy 0.03175 -0.89916) (xy 0.0635 -0.889) (xy 0.09144 -0.87376) (xy 0.11684 -0.85344) (xy 0.13716 -0.82804)
						(xy 0.1524 -0.8001) (xy 0.16256 -0.76835) (xy 0.1651 -0.7366) (xy 0.1651 -0.44958) (xy 0.17272 -0.44196)
						(xy 0.19812 -0.4064) (xy 0.2032 -0.39624) (xy 0.20701 -0.38735) (xy 0.21209 -0.37719) (xy 0.2159 -0.36703)
						(xy 0.21844 -0.35687) (xy 0.22225 -0.34544) (xy 0.22352 -0.33528) (xy 0.22606 -0.32512) (xy 0.22733 -0.31369)
						(xy 0.22733 -0.30353) (xy 0.2286 -0.2921) (xy 0.22733 -0.28067) (xy 0.22733 -0.27051) (xy 0.22606 -0.25908)
						(xy 0.22352 -0.24892) (xy 0.22225 -0.23876) (xy 0.21844 -0.22733) (xy 0.2159 -0.21717) (xy 0.21209 -0.20701)
						(xy 0.20701 -0.19685) (xy 0.2032 -0.18796) (xy 0.19812 -0.1778) (xy 0.17272 -0.14224) (xy 0.1651 -0.13462)
						(xy 0.1651 0.7366) (xy 0.16256 0.76835) (xy 0.1524 0.8001) (xy 0.13716 0.82804) (xy 0.11684 0.85344)
						(xy 0.09144 0.87376) (xy 0.0635 0.889) (xy 0.03175 0.89916)
					)
					(width 0)
					(fill yes)
				)
			)
		)
		(pad "118" smd custom
			(at 5.849874 -4.106672 180)
			(size 0.1143 0.1143)
			(layers "F.Cu" "F.Mask" "F.Paste")
			(net "Net_12")
			(options
				(clearance outline)
				(anchor circle)
			)
			(primitives
				(gr_poly
					(pts
						(xy 0 0.9017) (xy -0.03175 0.89916) (xy -0.0635 0.889) (xy -0.09144 0.87376) (xy -0.11684 0.85344)
						(xy -0.13716 0.82804) (xy -0.1524 0.8001) (xy -0.16256 0.76835) (xy -0.1651 0.7366) (xy -0.1651 0.44958)
						(xy -0.17272 0.44196) (xy -0.19812 0.4064) (xy -0.2032 0.39624) (xy -0.20701 0.38735) (xy -0.21209 0.37719)
						(xy -0.2159 0.36703) (xy -0.21844 0.35687) (xy -0.22225 0.34544) (xy -0.22352 0.33528) (xy -0.22606 0.32512)
						(xy -0.22733 0.31369) (xy -0.22733 0.30353) (xy -0.2286 0.2921) (xy -0.22733 0.28067) (xy -0.22733 0.27051)
						(xy -0.22606 0.25908) (xy -0.22352 0.24892) (xy -0.22225 0.23876) (xy -0.21844 0.22733) (xy -0.2159 0.21717)
						(xy -0.21209 0.20701) (xy -0.20701 0.19685) (xy -0.2032 0.18796) (xy -0.19812 0.1778) (xy -0.17272 0.14224)
						(xy -0.1651 0.13462) (xy -0.1651 -0.7366) (xy -0.16256 -0.76835) (xy -0.1524 -0.8001) (xy -0.13716 -0.82804)
						(xy -0.11684 -0.85344) (xy -0.09144 -0.87376) (xy -0.0635 -0.889) (xy -0.03175 -0.89916) (xy 0 -0.9017)
						(xy 0.03175 -0.89916) (xy 0.0635 -0.889) (xy 0.09144 -0.87376) (xy 0.11684 -0.85344) (xy 0.13716 -0.82804)
						(xy 0.1524 -0.8001) (xy 0.16256 -0.76835) (xy 0.1651 -0.7366) (xy 0.1651 0.13462) (xy 0.17272 0.14224)
						(xy 0.19812 0.1778) (xy 0.2032 0.18796) (xy 0.20701 0.19685) (xy 0.21209 0.20701) (xy 0.2159 0.21717)
						(xy 0.21844 0.22733) (xy 0.22225 0.23876) (xy 0.22352 0.24892) (xy 0.22606 0.25908) (xy 0.22733 0.27051)
						(xy 0.22733 0.28067) (xy 0.2286 0.2921) (xy 0.22733 0.30353) (xy 0.22733 0.31369) (xy 0.22606 0.32512)
						(xy 0.22352 0.33528) (xy 0.22225 0.34544) (xy 0.21844 0.35687) (xy 0.2159 0.36703) (xy 0.21209 0.37719)
						(xy 0.20701 0.38735) (xy 0.2032 0.39624) (xy 0.19812 0.4064) (xy 0.17272 0.44196) (xy 0.1651 0.44958)
						(xy 0.1651 0.7366) (xy 0.16256 0.76835) (xy 0.1524 0.8001) (xy 0.13716 0.82804) (xy 0.11684 0.85344)
						(xy 0.09144 0.87376) (xy 0.0635 0.889) (xy 0.03175 0.89916)
					)
					(width 0)
					(fill yes)
				)
			)
		)
	)
)
